(kicad_pcb
	(version 20260206)
	(generator "pcbnew")
	(generator_version "10.0")
	(general
		(thickness 1.6)
		(legacy_teardrops no)
	)
	(paper "A4")
	(title_block
		(title "01162023_DA0F0TEBIF0_F0T_Expander_BD_F_brd_V02_OCP.brd")
		(comment 1 "Grand Teton / footprints 2887-2892 of 9728")
	)
	(layers
		(0 "F.Cu" signal "TOP")
		(4 "In1.Cu" signal "GND")
		(6 "In2.Cu" signal "VCC")
		(8 "In3.Cu" signal "VCC1")
		(10 "In4.Cu" signal "GND1")
		(12 "In5.Cu" signal "IN1")
		(14 "In6.Cu" signal "GND2")
		(16 "In7.Cu" signal "IN2")
		(18 "In8.Cu" signal "GND3")
		(20 "In9.Cu" signal "IN3")
		(22 "In10.Cu" signal "GND4")
		(24 "In11.Cu" signal "IN4")
		(26 "In12.Cu" signal "GND5")
		(28 "In13.Cu" signal "IN5")
		(30 "In14.Cu" signal "GND6")
		(32 "In15.Cu" signal "IN6")
		(34 "In16.Cu" signal "GND7")
		(2 "B.Cu" signal "BOTTOM")
		(9 "F.Adhes" user "F.Adhesive")
		(11 "B.Adhes" user "B.Adhesive")
		(13 "F.Paste" user "Package Geometry/Pastemask Top")
		(15 "B.Paste" user "Package Geometry/Pastemask Bottom")
		(5 "F.SilkS" user "Ref Des/Silkscreen Top")
		(7 "B.SilkS" user "Ref Des/Silkscreen Bottom")
		(1 "F.Mask" user "Board Geometry/Soldermask Top")
		(3 "B.Mask" user "Board Geometry/Soldermask Bottom")
		(17 "Dwgs.User" user "User.Drawings")
		(19 "Cmts.User" user "User.Comments")
		(21 "Eco1.User" user "User.Eco1")
		(23 "Eco2.User" user "User.Eco2")
		(25 "Edge.Cuts" user "Board Geometry/Outline")
		(27 "Margin" user)
		(31 "F.CrtYd" user "Package Geometry/Place Bound Top")
		(29 "B.CrtYd" user "Package Geometry/Place Bound Bottom")
		(35 "F.Fab" user "Ref Des/Assembly Top")
		(33 "B.Fab" user "Ref Des/Assembly Bottom")
	)
	(footprint ""
		(layer "F.Cu")
		(at 455.238612 -254.5969 -90)
		(property "Reference" "C4396"
			(at 0 0 270)
			(layer "F.SilkS")
			(hide yes)
			(effects
				(font
					(size 1.27 1.27)
				)
			)
		)
		(property "Value" ""
			(at 0 0 270)
			(layer "F.Fab")
			(effects
				(font
					(size 1.27 1.27)
				)
			)
		)
		(duplicate_pad_numbers_are_jumpers no)
		(fp_line
			(start -1.2954 0.5842)
			(end -1.2954 -0.5842)
			(stroke
				(width 0.1524)
				(type default)
			)
			(layer "F.SilkS")
		)
		(fp_line
			(start 1.2954 0.5842)
			(end -1.2954 0.5842)
			(stroke
				(width 0.1524)
				(type default)
			)
			(layer "F.SilkS")
		)
		(fp_line
			(start -1.2954 -0.5842)
			(end 1.2954 -0.5842)
			(stroke
				(width 0.1524)
				(type default)
			)
			(layer "F.SilkS")
		)
		(fp_line
			(start 1.2954 -0.5842)
			(end 1.2954 0.5842)
			(stroke
				(width 0.1524)
				(type default)
			)
			(layer "F.SilkS")
		)
		(fp_line
			(start -0.8636 0.4572)
			(end -0.8636 0.4064)
			(stroke
				(width 0.1)
				(type default)
			)
			(layer "F.Fab")
		)
		(fp_line
			(start 0.8636 0.4572)
			(end -0.8636 0.4572)
			(stroke
				(width 0.1)
				(type default)
			)
			(layer "F.Fab")
		)
		(fp_line
			(start -1.1938 0.4064)
			(end -1.1938 -0.4064)
			(stroke
				(width 0.1)
				(type default)
			)
			(layer "F.Fab")
		)
		(fp_line
			(start -0.8636 0.4064)
			(end -1.1938 0.4064)
			(stroke
				(width 0.1)
				(type default)
			)
			(layer "F.Fab")
		)
		(fp_line
			(start 0.8636 0.4064)
			(end 0.8636 0.4572)
			(stroke
				(width 0.1)
				(type default)
			)
			(layer "F.Fab")
		)
		(fp_line
			(start 1.1938 0.4064)
			(end 0.8636 0.4064)
			(stroke
				(width 0.1)
				(type default)
			)
			(layer "F.Fab")
		)
		(fp_line
			(start -1.1938 -0.4064)
			(end -0.8636 -0.4064)
			(stroke
				(width 0.1)
				(type default)
			)
			(layer "F.Fab")
		)
		(fp_line
			(start -0.8636 -0.4064)
			(end -0.8636 -0.4572)
			(stroke
				(width 0.1)
				(type default)
			)
			(layer "F.Fab")
		)
		(fp_line
			(start 0.8636 -0.4064)
			(end 1.1938 -0.4064)
			(stroke
				(width 0.1)
				(type default)
			)
			(layer "F.Fab")
		)
		(fp_line
			(start 1.1938 -0.4064)
			(end 1.1938 0.4064)
			(stroke
				(width 0.1)
				(type default)
			)
			(layer "F.Fab")
		)
		(fp_line
			(start -0.8636 -0.4572)
			(end 0.8636 -0.4572)
			(stroke
				(width 0.1)
				(type default)
			)
			(layer "F.Fab")
		)
		(fp_line
			(start 0.8636 -0.4572)
			(end 0.8636 -0.4064)
			(stroke
				(width 0.1)
				(type default)
			)
			(layer "F.Fab")
		)
		(pad "1" smd rect
			(at -0.7366 0 180)
			(size 0.7112 0.8128)
			(layers "F.Cu" "F.Mask" "F.Paste")
			(net "P1V25_SERDES_VDDPLL_PEX3_C2")
		)
		(pad "2" smd rect
			(at 0.7366 0 180)
			(size 0.7112 0.8128)
			(layers "F.Cu" "F.Mask" "F.Paste")
			(net "GND")
		)
	)
	(footprint ""
		(layer "F.Cu")
		(at 147.107402 -257.439414 -90)
		(property "Reference" "C3226"
			(at 0 0 270)
			(layer "F.SilkS")
			(hide yes)
			(effects
				(font
					(size 1.27 1.27)
				)
			)
		)
		(property "Value" ""
			(at 0 0 270)
			(layer "F.Fab")
			(effects
				(font
					(size 1.27 1.27)
				)
			)
		)
		(duplicate_pad_numbers_are_jumpers no)
		(fp_line
			(start -0.299974 0.150114)
			(end -0.299974 -0.150114)
			(stroke
				(width 0.1)
				(type default)
			)
			(layer "F.Fab")
		)
		(fp_line
			(start 0.299974 0.150114)
			(end -0.299974 0.150114)
			(stroke
				(width 0.1)
				(type default)
			)
			(layer "F.Fab")
		)
		(fp_line
			(start -0.299974 -0.150114)
			(end 0.299974 -0.150114)
			(stroke
				(width 0.1)
				(type default)
			)
			(layer "F.Fab")
		)
		(fp_line
			(start 0.299974 -0.150114)
			(end 0.299974 0.150114)
			(stroke
				(width 0.1)
				(type default)
			)
			(layer "F.Fab")
		)
		(pad "1" smd rect
			(at -0.2667 0 270)
			(size 0.3048 0.381)
			(layers "F.Cu" "F.Mask" "F.Paste")
			(net "P1V8_PLL0_PEX1")
		)
		(pad "2" smd rect
			(at 0.2667 0 270)
			(size 0.3048 0.381)
			(layers "F.Cu" "F.Mask" "F.Paste")
			(net "GND")
		)
	)
	(footprint ""
		(layer "F.Cu")
		(at 165.76802 -18.437098)
		(property "Reference" "R1666"
			(at 0 0 0)
			(layer "F.SilkS")
			(hide yes)
			(effects
				(font
					(size 1.27 1.27)
				)
			)
		)
		(property "Value" ""
			(at 0 0 0)
			(layer "F.Fab")
			(effects
				(font
					(size 1.27 1.27)
				)
			)
		)
		(duplicate_pad_numbers_are_jumpers no)
		(fp_line
			(start -0.7874 -0.4064)
			(end 0.7874 -0.4064)
			(stroke
				(width 0.1524)
				(type default)
			)
			(layer "F.SilkS")
		)
		(fp_line
			(start -0.7874 0.4064)
			(end -0.7874 -0.4064)
			(stroke
				(width 0.1524)
				(type default)
			)
			(layer "F.SilkS")
		)
		(fp_line
			(start 0.7874 -0.4064)
			(end 0.7874 0.4064)
			(stroke
				(width 0.1524)
				(type default)
			)
			(layer "F.SilkS")
		)
		(fp_line
			(start 0.7874 0.4064)
			(end -0.7874 0.4064)
			(stroke
				(width 0.1524)
				(type default)
			)
			(layer "F.SilkS")
		)
		(fp_line
			(start -0.67945 -0.305054)
			(end -0.12065 -0.305054)
			(stroke
				(width 0.1)
				(type default)
			)
			(layer "F.Fab")
		)
		(fp_line
			(start -0.67945 0.3048)
			(end -0.67945 -0.305054)
			(stroke
				(width 0.1)
				(type default)
			)
			(layer "F.Fab")
		)
		(fp_line
			(start -0.12065 -0.305054)
			(end -0.12065 -0.2794)
			(stroke
				(width 0.1)
				(type default)
			)
			(layer "F.Fab")
		)
		(fp_line
			(start -0.12065 -0.2794)
			(end 0.12065 -0.2794)
			(stroke
				(width 0.1)
				(type default)
			)
			(layer "F.Fab")
		)
		(fp_line
			(start -0.12065 0.2794)
			(end -0.12065 0.3048)
			(stroke
				(width 0.1)
				(type default)
			)
			(layer "F.Fab")
		)
		(fp_line
			(start -0.12065 0.3048)
			(end -0.67945 0.3048)
			(stroke
				(width 0.1)
				(type default)
			)
			(layer "F.Fab")
		)
		(fp_line
			(start 0.120396 0.2794)
			(end -0.12065 0.2794)
			(stroke
				(width 0.1)
				(type default)
			)
			(layer "F.Fab")
		)
		(fp_line
			(start 0.120396 0.3048)
			(end 0.120396 0.2794)
			(stroke
				(width 0.1)
				(type default)
			)
			(layer "F.Fab")
		)
		(fp_line
			(start 0.12065 -0.3048)
			(end 0.67945 -0.3048)
			(stroke
				(width 0.1)
				(type default)
			)
			(layer "F.Fab")
		)
		(fp_line
			(start 0.12065 -0.2794)
			(end 0.12065 -0.3048)
			(stroke
				(width 0.1)
				(type default)
			)
			(layer "F.Fab")
		)
		(fp_line
			(start 0.67945 -0.3048)
			(end 0.67945 0.3048)
			(stroke
				(width 0.1)
				(type default)
			)
			(layer "F.Fab")
		)
		(fp_line
			(start 0.67945 0.3048)
			(end 0.120396 0.3048)
			(stroke
				(width 0.1)
				(type default)
			)
			(layer "F.Fab")
		)
		(pad "1" smd circle
			(at -0.40005 0)
			(size 0 0)
			(layers "F.Cu" "F.Mask" "F.Paste")
			(net "SMB_ISO_SSD5_R_SCL")
		)
		(pad "2" smd circle
			(at 0.40005 0)
			(size 0 0)
			(layers "F.Cu" "F.Mask" "F.Paste")
			(net "SMB_ISO_SSD5_SCL")
		)
	)
	(footprint ""
		(layer "F.Cu")
		(at 282.39339 -172.004482 -90)
		(property "Reference" "U31"
			(at 1.722882 -2.44348 90)
			(unlocked yes)
			(layer "F.SilkS")
			(effects
				(font
					(size 0.7874 0.5842)
					(thickness 0.1524)
				)
				(justify left)
			)
		)
		(property "Value" ""
			(at 0 0 270)
			(layer "F.Fab")
			(effects
				(font
					(size 1.27 1.27)
				)
			)
		)
		(duplicate_pad_numbers_are_jumpers no)
		(fp_line
			(start -2.0574 1.651)
			(end -2.0574 -1.651)
			(stroke
				(width 0.1524)
				(type default)
			)
			(layer "F.SilkS")
		)
		(fp_line
			(start 2.0574 1.651)
			(end -2.0574 1.651)
			(stroke
				(width 0.1524)
				(type default)
			)
			(layer "F.SilkS")
		)
		(fp_line
			(start 0 -1.016)
			(end 0.381 -1.651)
			(stroke
				(width 0.1524)
				(type default)
			)
			(layer "F.SilkS")
		)
		(fp_line
			(start -2.0574 -1.651)
			(end -0.381 -1.651)
			(stroke
				(width 0.1524)
				(type default)
			)
			(layer "F.SilkS")
		)
		(fp_line
			(start -0.381 -1.651)
			(end 0 -1.016)
			(stroke
				(width 0.1524)
				(type default)
			)
			(layer "F.SilkS")
		)
		(fp_line
			(start 0.381 -1.651)
			(end 2.0574 -1.651)
			(stroke
				(width 0.1524)
				(type default)
			)
			(layer "F.SilkS")
		)
		(fp_line
			(start 2.0574 -1.651)
			(end 2.0574 1.651)
			(stroke
				(width 0.1524)
				(type default)
			)
			(layer "F.SilkS")
		)
		(fp_poly
			(pts
				(xy -2.71272 -0.719328) (xy -2.71272 -1.344168) (xy -2.159 -1.016)
			)
			(stroke
				(width 0)
				(type default)
			)
			(fill yes)
			(layer "F.SilkS")
		)
		(fp_line
			(start -0.899922 1.549908)
			(end -0.899922 1.199896)
			(stroke
				(width 0.1)
				(type default)
			)
			(layer "F.Fab")
		)
		(fp_line
			(start 0.899922 1.549908)
			(end -0.899922 1.549908)
			(stroke
				(width 0.1)
				(type default)
			)
			(layer "F.Fab")
		)
		(fp_line
			(start -1.599946 1.199896)
			(end -1.599946 -1.199896)
			(stroke
				(width 0.1)
				(type default)
			)
			(layer "F.Fab")
		)
		(fp_line
			(start -0.899922 1.199896)
			(end -1.599946 1.199896)
			(stroke
				(width 0.1)
				(type default)
			)
			(layer "F.Fab")
		)
		(fp_line
			(start 0.899922 1.199896)
			(end 0.899922 1.549908)
			(stroke
				(width 0.1)
				(type default)
			)
			(layer "F.Fab")
		)
		(fp_line
			(start 1.599946 1.199896)
			(end 0.899922 1.199896)
			(stroke
				(width 0.1)
				(type default)
			)
			(layer "F.Fab")
		)
		(fp_line
			(start -1.599946 -1.199896)
			(end -0.899922 -1.199896)
			(stroke
				(width 0.1)
				(type default)
			)
			(layer "F.Fab")
		)
		(fp_line
			(start -0.899922 -1.199896)
			(end -0.899922 -1.549908)
			(stroke
				(width 0.1)
				(type default)
			)
			(layer "F.Fab")
		)
		(fp_line
			(start 0.899922 -1.199896)
			(end 1.599946 -1.199896)
			(stroke
				(width 0.1)
				(type default)
			)
			(layer "F.Fab")
		)
		(fp_line
			(start 1.599946 -1.199896)
			(end 1.599946 1.199896)
			(stroke
				(width 0.1)
				(type default)
			)
			(layer "F.Fab")
		)
		(fp_line
			(start -0.899922 -1.549908)
			(end 0.899922 -1.549908)
			(stroke
				(width 0.1)
				(type default)
			)
			(layer "F.Fab")
		)
		(fp_line
			(start 0.899922 -1.549908)
			(end 0.899922 -1.199896)
			(stroke
				(width 0.1)
				(type default)
			)
			(layer "F.Fab")
		)
		(fp_poly
			(pts
				(xy -2.71272 -0.719328) (xy -2.71272 -1.344168) (xy -2.159 -1.016)
			)
			(stroke
				(width 0)
				(type default)
			)
			(fill yes)
			(layer "F.Fab")
		)
		(pad "1" smd rect
			(at -1.225042 -0.94996 180)
			(size 0.5588 1.3462)
			(layers "F.Cu" "F.Mask" "F.Paste")
			(net "HP_NIC4_PWRGD_R")
		)
		(pad "2" smd rect
			(at -1.225042 0 180)
			(size 0.5588 1.3462)
			(layers "F.Cu" "F.Mask" "F.Paste")
			(net "RST_NIC4_PERST_R_N")
		)
		(pad "3" smd rect
			(at -1.225042 0.94996 180)
			(size 0.5588 1.3462)
			(layers "F.Cu" "F.Mask" "F.Paste")
			(net "GND")
		)
		(pad "4" smd rect
			(at 1.225042 0.94996 180)
			(size 0.5588 1.3462)
			(layers "F.Cu" "F.Mask" "F.Paste")
			(net "RST_HP_NIC4_N")
		)
		(pad "5" smd rect
			(at 1.225042 -0.94996 180)
			(size 0.5588 1.3462)
			(layers "F.Cu" "F.Mask" "F.Paste")
			(net "P3V3_AUX")
		)
	)
	(footprint ""
		(layer "F.Cu")
		(at 34.502344 -252.356874 -90)
		(property "Reference" "R1233"
			(at 0 0 270)
			(layer "F.SilkS")
			(hide yes)
			(effects
				(font
					(size 1.27 1.27)
				)
			)
		)
		(property "Value" ""
			(at 0 0 270)
			(layer "F.Fab")
			(effects
				(font
					(size 1.27 1.27)
				)
			)
		)
		(duplicate_pad_numbers_are_jumpers no)
		(fp_line
			(start -0.7874 0.4064)
			(end -0.7874 -0.4064)
			(stroke
				(width 0.1524)
				(type default)
			)
			(layer "F.SilkS")
		)
		(fp_line
			(start 0.7874 0.4064)
			(end -0.7874 0.4064)
			(stroke
				(width 0.1524)
				(type default)
			)
			(layer "F.SilkS")
		)
		(fp_line
			(start -0.7874 -0.4064)
			(end 0.7874 -0.4064)
			(stroke
				(width 0.1524)
				(type default)
			)
			(layer "F.SilkS")
		)
		(fp_line
			(start 0.7874 -0.4064)
			(end 0.7874 0.4064)
			(stroke
				(width 0.1524)
				(type default)
			)
			(layer "F.SilkS")
		)
		(fp_line
			(start -0.67945 0.3048)
			(end -0.67945 -0.305054)
			(stroke
				(width 0.1)
				(type default)
			)
			(layer "F.Fab")
		)
		(fp_line
			(start -0.12065 0.3048)
			(end -0.67945 0.3048)
			(stroke
				(width 0.1)
				(type default)
			)
			(layer "F.Fab")
		)
		(fp_line
			(start 0.120396 0.3048)
			(end 0.120396 0.2794)
			(stroke
				(width 0.1)
				(type default)
			)
			(layer "F.Fab")
		)
		(fp_line
			(start 0.67945 0.3048)
			(end 0.120396 0.3048)
			(stroke
				(width 0.1)
				(type default)
			)
			(layer "F.Fab")
		)
		(fp_line
			(start -0.12065 0.2794)
			(end -0.12065 0.3048)
			(stroke
				(width 0.1)
				(type default)
			)
			(layer "F.Fab")
		)
		(fp_line
			(start 0.120396 0.2794)
			(end -0.12065 0.2794)
			(stroke
				(width 0.1)
				(type default)
			)
			(layer "F.Fab")
		)
		(fp_line
			(start -0.12065 -0.2794)
			(end 0.12065 -0.2794)
			(stroke
				(width 0.1)
				(type default)
			)
			(layer "F.Fab")
		)
		(fp_line
			(start 0.12065 -0.2794)
			(end 0.12065 -0.3048)
			(stroke
				(width 0.1)
				(type default)
			)
			(layer "F.Fab")
		)
		(fp_line
			(start 0.12065 -0.3048)
			(end 0.67945 -0.3048)
			(stroke
				(width 0.1)
				(type default)
			)
			(layer "F.Fab")
		)
		(fp_line
			(start 0.67945 -0.3048)
			(end 0.67945 0.3048)
			(stroke
				(width 0.1)
				(type default)
			)
			(layer "F.Fab")
		)
		(fp_line
			(start -0.67945 -0.305054)
			(end -0.12065 -0.305054)
			(stroke
				(width 0.1)
				(type default)
			)
			(layer "F.Fab")
		)
		(fp_line
			(start -0.12065 -0.305054)
			(end -0.12065 -0.2794)
			(stroke
				(width 0.1)
				(type default)
			)
			(layer "F.Fab")
		)
		(pad "1" smd circle
			(at -0.40005 0 270)
			(size 0 0)
			(layers "F.Cu" "F.Mask" "F.Paste")
			(net "GND")
		)
		(pad "2" smd circle
			(at 0.40005 0 270)
			(size 0 0)
			(layers "F.Cu" "F.Mask" "F.Paste")
			(net "PEX0_MODE_SEL11")
		)
	)
	(footprint ""
		(layer "F.Cu")
		(at 341.336884 -116.230654 90)
		(property "Reference" "R5967"
			(at 0 0 90)
			(layer "F.SilkS")
			(hide yes)
			(effects
				(font
					(size 1.27 1.27)
				)
			)
		)
		(property "Value" ""
			(at 0 0 90)
			(layer "F.Fab")
			(effects
				(font
					(size 1.27 1.27)
				)
			)
		)
		(duplicate_pad_numbers_are_jumpers no)
		(fp_line
			(start 0.7874 -0.4064)
			(end 0.7874 0.4064)
			(stroke
				(width 0.1524)
				(type default)
			)
			(layer "F.SilkS")
		)
		(fp_line
			(start -0.7874 -0.4064)
			(end 0.7874 -0.4064)
			(stroke
				(width 0.1524)
				(type default)
			)
			(layer "F.SilkS")
		)
		(fp_line
			(start 0.7874 0.4064)
			(end -0.7874 0.4064)
			(stroke
				(width 0.1524)
				(type default)
			)
			(layer "F.SilkS")
		)
		(fp_line
			(start -0.7874 0.4064)
			(end -0.7874 -0.4064)
			(stroke
				(width 0.1524)
				(type default)
			)
			(layer "F.SilkS")
		)
		(fp_line
			(start -0.12065 -0.305054)
			(end -0.12065 -0.2794)
			(stroke
				(width 0.1)
				(type default)
			)
			(layer "F.Fab")
		)
		(fp_line
			(start -0.67945 -0.305054)
			(end -0.12065 -0.305054)
			(stroke
				(width 0.1)
				(type default)
			)
			(layer "F.Fab")
		)
		(fp_line
			(start 0.67945 -0.3048)
			(end 0.67945 0.3048)
			(stroke
				(width 0.1)
				(type default)
			)
			(layer "F.Fab")
		)
		(fp_line
			(start 0.12065 -0.3048)
			(end 0.67945 -0.3048)
			(stroke
				(width 0.1)
				(type default)
			)
			(layer "F.Fab")
		)
		(fp_line
			(start 0.12065 -0.2794)
			(end 0.12065 -0.3048)
			(stroke
				(width 0.1)
				(type default)
			)
			(layer "F.Fab")
		)
		(fp_line
			(start -0.12065 -0.2794)
			(end 0.12065 -0.2794)
			(stroke
				(width 0.1)
				(type default)
			)
			(layer "F.Fab")
		)
		(fp_line
			(start 0.120396 0.2794)
			(end -0.12065 0.2794)
			(stroke
				(width 0.1)
				(type default)
			)
			(layer "F.Fab")
		)
		(fp_line
			(start -0.12065 0.2794)
			(end -0.12065 0.3048)
			(stroke
				(width 0.1)
				(type default)
			)
			(layer "F.Fab")
		)
		(fp_line
			(start 0.67945 0.3048)
			(end 0.120396 0.3048)
			(stroke
				(width 0.1)
				(type default)
			)
			(layer "F.Fab")
		)
		(fp_line
			(start 0.120396 0.3048)
			(end 0.120396 0.2794)
			(stroke
				(width 0.1)
				(type default)
			)
			(layer "F.Fab")
		)
		(fp_line
			(start -0.12065 0.3048)
			(end -0.67945 0.3048)
			(stroke
				(width 0.1)
				(type default)
			)
			(layer "F.Fab")
		)
		(fp_line
			(start -0.67945 0.3048)
			(end -0.67945 -0.305054)
			(stroke
				(width 0.1)
				(type default)
			)
			(layer "F.Fab")
		)
		(pad "1" smd circle
			(at -0.40005 0 90)
			(size 0 0)
			(layers "F.Cu" "F.Mask" "F.Paste")
			(net "PWRGD_P12V_NIC5_CO")
		)
		(pad "2" smd circle
			(at 0.40005 0 90)
			(size 0 0)
			(layers "F.Cu" "F.Mask" "F.Paste")
			(net "PWRGD_P12V_NIC5_R")
		)
	)
)
